(kicad_pcb
	(version 20260206)
	(generator "pcbnew")
	(generator_version "10.0")
	(general
		(thickness 1.6)
		(legacy_teardrops no)
	)
	(paper "A4")
	(title_block
		(title "peb — Lightning_PEB_BRD.brd")
		(comment 1 "Lightning (Wiwynn / Facebook NVMe JBOF) / footprints 2231-2238 of 2563")
	)
	(layers
		(0 "F.Cu" signal "TOP")
		(4 "In1.Cu" signal "L2GND")
		(6 "In2.Cu" signal "L3")
		(8 "In3.Cu" signal "L4VCC")
		(10 "In4.Cu" signal "L5VCC")
		(12 "In5.Cu" signal "L6")
		(14 "In6.Cu" signal "L7GND")
		(2 "B.Cu" signal "BOTTOM")
		(9 "F.Adhes" user "F.Adhesive")
		(11 "B.Adhes" user "B.Adhesive")
		(13 "F.Paste" user "Package Geometry/Pastemask Top")
		(15 "B.Paste" user "Package Geometry/Pastemask Bottom")
		(5 "F.SilkS" user "Ref Des/Silkscreen Top")
		(7 "B.SilkS" user "Ref Des/Silkscreen Bottom")
		(1 "F.Mask" user "Board Geometry/Soldermask Top")
		(3 "B.Mask" user "Board Geometry/Soldermask Bottom")
		(17 "Dwgs.User" user "User.Drawings")
		(19 "Cmts.User" user "User.Comments")
		(21 "Eco1.User" user "User.Eco1")
		(23 "Eco2.User" user "User.Eco2")
		(25 "Edge.Cuts" user "Board Geometry/Outline")
		(27 "Margin" user)
		(31 "F.CrtYd" user "Package Geometry/Place Bound Top")
		(29 "B.CrtYd" user "Package Geometry/Place Bound Bottom")
		(35 "F.Fab" user "Ref Des/Assembly Top")
		(33 "B.Fab" user "Ref Des/Assembly Bottom")
	)
	(footprint ""
		(layer "B.Cu")
		(at 239.1664 -43.997372 90)
		(property "Reference" "C429"
			(at 0 0 90)
			(layer "B.SilkS")
			(hide yes)
			(effects
				(font
					(size 1.27 1.27)
				)
				(justify mirror)
			)
		)
		(property "Value" "SCD1U16V1KX-1-GP"
			(at 2.8321 -1.7399 90)
			(unlocked yes)
			(layer "B.Fab")
			(hide yes)
			(effects
				(font
					(size 1.016 1.016)
					(thickness 0.1524)
				)
				(justify mirror)
			)
		)
		(property "Device Type" "C0201H13"
			(at 2.8321 -3.2639 90)
			(unlocked yes)
			(layer "B.Fab")
			(hide yes)
			(effects
				(font
					(size 1.016 1.016)
					(thickness 0.1524)
				)
				(justify mirror)
			)
		)
		(duplicate_pad_numbers_are_jumpers no)
		(fp_rect
			(start 0.2794 0.6477)
			(end -0.2794 -0.6477)
			(stroke
				(width 0)
				(type default)
			)
			(fill no)
			(layer "B.CrtYd")
		)
		(fp_rect
			(start 0.2794 0.6477)
			(end -0.2794 -0.6477)
			(stroke
				(width 0)
				(type default)
			)
			(fill no)
			(layer "B.Fab")
		)
		(pad "1" smd custom
			(at 0 -0.2794 270)
			(size 0.0762 0.0762)
			(layers "B.Cu" "B.Mask" "B.Paste")
			(net "DUT_VDD")
			(options
				(clearance outline)
				(anchor circle)
			)
			(primitives
				(gr_poly
					(pts
						(arc
							(start 0.1524 0.127)
							(mid 0.137521 0.162921)
							(end 0.1016 0.1778)
						)
						(arc
							(start -0.1016 0.1778)
							(mid -0.137521 0.162921)
							(end -0.1524 0.127)
						)
						(arc
							(start -0.1524 -0.127)
							(mid -0.137521 -0.162921)
							(end -0.1016 -0.1778)
						)
						(arc
							(start 0.1016 -0.1778)
							(mid 0.137521 -0.162921)
							(end 0.1524 -0.127)
						)
					)
					(width 0)
					(fill yes)
				)
			)
		)
		(pad "2" smd custom
			(at 0 0.2794 270)
			(size 0.0762 0.0762)
			(layers "B.Cu" "B.Mask" "B.Paste")
			(net "GND")
			(options
				(clearance outline)
				(anchor circle)
			)
			(primitives
				(gr_poly
					(pts
						(arc
							(start 0.1524 0.127)
							(mid 0.137521 0.162921)
							(end 0.1016 0.1778)
						)
						(arc
							(start -0.1016 0.1778)
							(mid -0.137521 0.162921)
							(end -0.1524 0.127)
						)
						(arc
							(start -0.1524 -0.127)
							(mid -0.137521 -0.162921)
							(end -0.1016 -0.1778)
						)
						(arc
							(start 0.1016 -0.1778)
							(mid 0.137521 -0.162921)
							(end 0.1524 -0.127)
						)
					)
					(width 0)
					(fill yes)
				)
			)
		)
	)
	(footprint ""
		(layer "B.Cu")
		(at 333.788512 -172.432218)
		(property "Reference" "R4151"
			(at 0 0 0)
			(layer "B.SilkS")
			(hide yes)
			(effects
				(font
					(size 1.27 1.27)
				)
				(justify mirror)
			)
		)
		(property "Value" "4K7R2F-GP"
			(at -0.064008 -3.993896 0)
			(unlocked yes)
			(layer "B.Fab")
			(hide yes)
			(effects
				(font
					(size 1.016 1.016)
					(thickness 0.1524)
				)
				(justify mirror)
			)
		)
		(property "Device Type" "R402H16"
			(at -0.064008 -5.517896 0)
			(unlocked yes)
			(layer "B.Fab")
			(hide yes)
			(effects
				(font
					(size 1.016 1.016)
					(thickness 0.1524)
				)
				(justify mirror)
			)
		)
		(duplicate_pad_numbers_are_jumpers no)
		(fp_line
			(start -0.508 -0.9398)
			(end 0.508 -0.9398)
			(stroke
				(width 0.1524)
				(type default)
			)
			(layer "B.SilkS")
		)
		(fp_line
			(start 0.508 -0.9398)
			(end 0.508 0.9398)
			(stroke
				(width 0.1524)
				(type default)
			)
			(layer "B.SilkS")
		)
		(fp_rect
			(start 0.508 0.9398)
			(end -0.508 -0.9398)
			(stroke
				(width 0)
				(type default)
			)
			(fill no)
			(layer "B.CrtYd")
		)
		(fp_rect
			(start 0.508 0.9398)
			(end -0.508 -0.9398)
			(stroke
				(width 0)
				(type default)
			)
			(fill no)
			(layer "B.Fab")
		)
		(pad "1" smd custom
			(at 0 -0.4445 180)
			(size 0.1397 0.1397)
			(layers "B.Cu" "B.Mask" "B.Paste")
			(net "SSD_ATNLED#4")
			(options
				(clearance outline)
				(anchor circle)
			)
			(primitives
				(gr_poly
					(pts
						(arc
							(start -0.1778 0.2794)
							(mid -0.249642 0.249642)
							(end -0.2794 0.1778)
						)
						(arc
							(start -0.2794 -0.1778)
							(mid -0.249642 -0.249642)
							(end -0.1778 -0.2794)
						)
						(arc
							(start 0.1778 -0.2794)
							(mid 0.249642 -0.249642)
							(end 0.2794 -0.1778)
						)
						(arc
							(start 0.2794 0.1778)
							(mid 0.249642 0.249642)
							(end 0.1778 0.2794)
						)
					)
					(width 0)
					(fill yes)
				)
			)
		)
		(pad "2" smd custom
			(at 0 0.4445 180)
			(size 0.1397 0.1397)
			(layers "B.Cu" "B.Mask" "B.Paste")
			(net "P3V3_STBY")
			(options
				(clearance outline)
				(anchor circle)
			)
			(primitives
				(gr_poly
					(pts
						(arc
							(start -0.1778 0.2794)
							(mid -0.249642 0.249642)
							(end -0.2794 0.1778)
						)
						(arc
							(start -0.2794 -0.1778)
							(mid -0.249642 -0.249642)
							(end -0.1778 -0.2794)
						)
						(arc
							(start 0.1778 -0.2794)
							(mid 0.249642 -0.249642)
							(end 0.2794 -0.1778)
						)
						(arc
							(start 0.2794 0.1778)
							(mid 0.249642 0.249642)
							(end 0.1778 0.2794)
						)
					)
					(width 0)
					(fill yes)
				)
			)
		)
	)
	(footprint ""
		(layer "B.Cu")
		(at 70.1548 -39.8526 180)
		(property "Reference" "PC28"
			(at 0 0 0)
			(layer "B.SilkS")
			(hide yes)
			(effects
				(font
					(size 1.27 1.27)
				)
				(justify mirror)
			)
		)
		(property "Value" "SC2K2P50V3KX-GP"
			(at 0 -2.8194 180)
			(unlocked yes)
			(layer "B.Fab")
			(hide yes)
			(effects
				(font
					(size 1.016 1.016)
					(thickness 0.1524)
				)
				(justify mirror)
			)
		)
		(property "Device Type" "C603"
			(at 0 -4.3434 180)
			(unlocked yes)
			(layer "B.Fab")
			(hide yes)
			(effects
				(font
					(size 1.016 1.016)
					(thickness 0.1524)
				)
				(justify mirror)
			)
		)
		(duplicate_pad_numbers_are_jumpers no)
		(fp_line
			(start -0.508 0)
			(end 0.508 0)
			(stroke
				(width 0.2032)
				(type default)
			)
			(layer "B.SilkS")
		)
		(fp_rect
			(start 0.5842 1.3335)
			(end -0.5842 -1.3335)
			(stroke
				(width 0)
				(type default)
			)
			(fill no)
			(layer "B.CrtYd")
		)
		(fp_rect
			(start 0.5842 1.3335)
			(end -0.5842 -1.3335)
			(stroke
				(width 0)
				(type default)
			)
			(fill no)
			(layer "B.Fab")
		)
		(pad "1" smd custom
			(at 0 -0.762)
			(size 0.2159 0.2159)
			(layers "B.Cu" "B.Mask" "B.Paste")
			(net "P3V3_STBY_LL")
			(options
				(clearance outline)
				(anchor circle)
			)
			(primitives
				(gr_poly
					(pts
						(arc
							(start -0.3302 0.4318)
							(mid -0.402042 0.402042)
							(end -0.4318 0.3302)
						)
						(arc
							(start -0.4318 -0.3302)
							(mid -0.402042 -0.402042)
							(end -0.3302 -0.4318)
						)
						(arc
							(start 0.3302 -0.4318)
							(mid 0.402042 -0.402042)
							(end 0.4318 -0.3302)
						)
						(arc
							(start 0.4318 0.3302)
							(mid 0.402042 0.402042)
							(end 0.3302 0.4318)
						)
					)
					(width 0)
					(fill yes)
				)
			)
		)
		(pad "2" smd custom
			(at 0 0.762)
			(size 0.2159 0.2159)
			(layers "B.Cu" "B.Mask" "B.Paste")
			(net "P3V3_STBY_SNB")
			(options
				(clearance outline)
				(anchor circle)
			)
			(primitives
				(gr_poly
					(pts
						(arc
							(start -0.3302 0.4318)
							(mid -0.402042 0.402042)
							(end -0.4318 0.3302)
						)
						(arc
							(start -0.4318 -0.3302)
							(mid -0.402042 -0.402042)
							(end -0.3302 -0.4318)
						)
						(arc
							(start 0.3302 -0.4318)
							(mid 0.402042 -0.402042)
							(end 0.4318 -0.3302)
						)
						(arc
							(start 0.4318 0.3302)
							(mid 0.402042 0.402042)
							(end 0.3302 0.4318)
						)
					)
					(width 0)
					(fill yes)
				)
			)
		)
	)
	(footprint ""
		(layer "B.Cu")
		(at 238.4044 -25.273 90)
		(property "Reference" "TP207"
			(at 0 0 90)
			(layer "B.SilkS")
			(hide yes)
			(effects
				(font
					(size 1.27 1.27)
				)
				(justify mirror)
			)
		)
		(property "Value" "TPAD28-2-GP"
			(at 0.0127 -1.6637 90)
			(unlocked yes)
			(layer "B.Fab")
			(hide yes)
			(effects
				(font
					(size 1.016 1.016)
					(thickness 0.1524)
				)
				(justify mirror)
			)
		)
		(property "Device Type" "TPAD28"
			(at 0.0127 -3.1877 90)
			(unlocked yes)
			(layer "B.Fab")
			(hide yes)
			(effects
				(font
					(size 1.016 1.016)
					(thickness 0.1524)
				)
				(justify mirror)
			)
		)
		(duplicate_pad_numbers_are_jumpers no)
		(fp_poly
			(pts
				(arc
					(start 0 0.3556)
					(mid 0 -0.3556)
					(end 0 0.3556)
				)
			)
			(stroke
				(width 0)
				(type default)
			)
			(fill no)
			(layer "B.CrtYd")
		)
		(fp_poly
			(pts
				(arc
					(start 0 0.6096)
					(mid 0 -0.6096)
					(end 0 0.6096)
				)
			)
			(stroke
				(width 0)
				(type default)
			)
			(fill no)
			(layer "B.Fab")
		)
		(pad "1" smd circle
			(at 0 0 270)
			(size 0.7112 0.7112)
			(layers "B.Cu" "B.Mask" "B.Paste")
			(net "LBI_DATA15")
		)
	)
	(footprint ""
		(layer "B.Cu")
		(at 228.6254 -55.998872 90)
		(property "Reference" "C536"
			(at 0 0 90)
			(layer "B.SilkS")
			(hide yes)
			(effects
				(font
					(size 1.27 1.27)
				)
				(justify mirror)
			)
		)
		(property "Value" "SCD1U16V1KX-1-GP"
			(at 2.8321 -1.7399 90)
			(unlocked yes)
			(layer "B.Fab")
			(hide yes)
			(effects
				(font
					(size 1.016 1.016)
					(thickness 0.1524)
				)
				(justify mirror)
			)
		)
		(property "Device Type" "C0201H13"
			(at 2.8321 -3.2639 90)
			(unlocked yes)
			(layer "B.Fab")
			(hide yes)
			(effects
				(font
					(size 1.016 1.016)
					(thickness 0.1524)
				)
				(justify mirror)
			)
		)
		(duplicate_pad_numbers_are_jumpers no)
		(fp_rect
			(start 0.2794 0.6477)
			(end -0.2794 -0.6477)
			(stroke
				(width 0)
				(type default)
			)
			(fill no)
			(layer "B.CrtYd")
		)
		(fp_rect
			(start 0.2794 0.6477)
			(end -0.2794 -0.6477)
			(stroke
				(width 0)
				(type default)
			)
			(fill no)
			(layer "B.Fab")
		)
		(pad "1" smd custom
			(at 0 -0.2794 270)
			(size 0.0762 0.0762)
			(layers "B.Cu" "B.Mask" "B.Paste")
			(net "DUT_AVD_PCIE")
			(options
				(clearance outline)
				(anchor circle)
			)
			(primitives
				(gr_poly
					(pts
						(arc
							(start 0.1524 0.127)
							(mid 0.137521 0.162921)
							(end 0.1016 0.1778)
						)
						(arc
							(start -0.1016 0.1778)
							(mid -0.137521 0.162921)
							(end -0.1524 0.127)
						)
						(arc
							(start -0.1524 -0.127)
							(mid -0.137521 -0.162921)
							(end -0.1016 -0.1778)
						)
						(arc
							(start 0.1016 -0.1778)
							(mid 0.137521 -0.162921)
							(end 0.1524 -0.127)
						)
					)
					(width 0)
					(fill yes)
				)
			)
		)
		(pad "2" smd custom
			(at 0 0.2794 270)
			(size 0.0762 0.0762)
			(layers "B.Cu" "B.Mask" "B.Paste")
			(net "GND")
			(options
				(clearance outline)
				(anchor circle)
			)
			(primitives
				(gr_poly
					(pts
						(arc
							(start 0.1524 0.127)
							(mid 0.137521 0.162921)
							(end 0.1016 0.1778)
						)
						(arc
							(start -0.1016 0.1778)
							(mid -0.137521 0.162921)
							(end -0.1524 0.127)
						)
						(arc
							(start -0.1524 -0.127)
							(mid -0.137521 -0.162921)
							(end -0.1016 -0.1778)
						)
						(arc
							(start 0.1016 -0.1778)
							(mid 0.137521 -0.162921)
							(end 0.1524 -0.127)
						)
					)
					(width 0)
					(fill yes)
				)
			)
		)
	)
	(footprint ""
		(layer "B.Cu")
		(at 131.52628 -33.54578)
		(property "Reference" "R2917"
			(at 0 0 0)
			(layer "B.SilkS")
			(hide yes)
			(effects
				(font
					(size 1.27 1.27)
				)
				(justify mirror)
			)
		)
		(property "Value" "0R2J-2-GP"
			(at -0.064008 -3.993896 0)
			(unlocked yes)
			(layer "B.Fab")
			(hide yes)
			(effects
				(font
					(size 1.016 1.016)
					(thickness 0.1524)
				)
				(justify mirror)
			)
		)
		(property "Device Type" "R402H16"
			(at -0.064008 -5.517896 0)
			(unlocked yes)
			(layer "B.Fab")
			(hide yes)
			(effects
				(font
					(size 1.016 1.016)
					(thickness 0.1524)
				)
				(justify mirror)
			)
		)
		(duplicate_pad_numbers_are_jumpers no)
		(fp_line
			(start -0.508 -0.9398)
			(end 0.508 -0.9398)
			(stroke
				(width 0.1524)
				(type default)
			)
			(layer "B.SilkS")
		)
		(fp_line
			(start 0.508 -0.9398)
			(end 0.508 0.9398)
			(stroke
				(width 0.1524)
				(type default)
			)
			(layer "B.SilkS")
		)
		(fp_rect
			(start 0.508 0.9398)
			(end -0.508 -0.9398)
			(stroke
				(width 0)
				(type default)
			)
			(fill no)
			(layer "B.CrtYd")
		)
		(fp_rect
			(start 0.508 0.9398)
			(end -0.508 -0.9398)
			(stroke
				(width 0)
				(type default)
			)
			(fill no)
			(layer "B.Fab")
		)
		(pad "1" smd custom
			(at 0 -0.4445 180)
			(size 0.1397 0.1397)
			(layers "B.Cu" "B.Mask" "B.Paste")
			(net "BMC_I2C1_MINI1_SDA")
			(options
				(clearance outline)
				(anchor circle)
			)
			(primitives
				(gr_poly
					(pts
						(arc
							(start -0.1778 0.2794)
							(mid -0.249642 0.249642)
							(end -0.2794 0.1778)
						)
						(arc
							(start -0.2794 -0.1778)
							(mid -0.249642 -0.249642)
							(end -0.1778 -0.2794)
						)
						(arc
							(start 0.1778 -0.2794)
							(mid 0.249642 -0.249642)
							(end 0.2794 -0.1778)
						)
						(arc
							(start 0.2794 0.1778)
							(mid 0.249642 0.249642)
							(end 0.1778 0.2794)
						)
					)
					(width 0)
					(fill yes)
				)
			)
		)
		(pad "2" smd custom
			(at 0 0.4445 180)
			(size 0.1397 0.1397)
			(layers "B.Cu" "B.Mask" "B.Paste")
			(net "8644_SDA_R_1")
			(options
				(clearance outline)
				(anchor circle)
			)
			(primitives
				(gr_poly
					(pts
						(arc
							(start -0.1778 0.2794)
							(mid -0.249642 0.249642)
							(end -0.2794 0.1778)
						)
						(arc
							(start -0.2794 -0.1778)
							(mid -0.249642 -0.249642)
							(end -0.1778 -0.2794)
						)
						(arc
							(start 0.1778 -0.2794)
							(mid 0.249642 -0.249642)
							(end 0.2794 -0.1778)
						)
						(arc
							(start 0.2794 0.1778)
							(mid 0.249642 0.249642)
							(end 0.1778 0.2794)
						)
					)
					(width 0)
					(fill yes)
				)
			)
		)
	)
	(footprint ""
		(layer "B.Cu")
		(at 245.5672 -56.007 90)
		(property "Reference" "C523"
			(at 0 0 90)
			(layer "B.SilkS")
			(hide yes)
			(effects
				(font
					(size 1.27 1.27)
				)
				(justify mirror)
			)
		)
		(property "Value" "SCD1U16V1KX-1-GP"
			(at 2.8321 -1.7399 90)
			(unlocked yes)
			(layer "B.Fab")
			(hide yes)
			(effects
				(font
					(size 1.016 1.016)
					(thickness 0.1524)
				)
				(justify mirror)
			)
		)
		(property "Device Type" "C0201H13"
			(at 2.8321 -3.2639 90)
			(unlocked yes)
			(layer "B.Fab")
			(hide yes)
			(effects
				(font
					(size 1.016 1.016)
					(thickness 0.1524)
				)
				(justify mirror)
			)
		)
		(duplicate_pad_numbers_are_jumpers no)
		(fp_rect
			(start 0.2794 0.6477)
			(end -0.2794 -0.6477)
			(stroke
				(width 0)
				(type default)
			)
			(fill no)
			(layer "B.CrtYd")
		)
		(fp_rect
			(start 0.2794 0.6477)
			(end -0.2794 -0.6477)
			(stroke
				(width 0)
				(type default)
			)
			(fill no)
			(layer "B.Fab")
		)
		(pad "1" smd custom
			(at 0 -0.2794 270)
			(size 0.0762 0.0762)
			(layers "B.Cu" "B.Mask" "B.Paste")
			(net "DUT_AVD_TX")
			(options
				(clearance outline)
				(anchor circle)
			)
			(primitives
				(gr_poly
					(pts
						(arc
							(start 0.1524 0.127)
							(mid 0.137521 0.162921)
							(end 0.1016 0.1778)
						)
						(arc
							(start -0.1016 0.1778)
							(mid -0.137521 0.162921)
							(end -0.1524 0.127)
						)
						(arc
							(start -0.1524 -0.127)
							(mid -0.137521 -0.162921)
							(end -0.1016 -0.1778)
						)
						(arc
							(start 0.1016 -0.1778)
							(mid 0.137521 -0.162921)
							(end 0.1524 -0.127)
						)
					)
					(width 0)
					(fill yes)
				)
			)
		)
		(pad "2" smd custom
			(at 0 0.2794 270)
			(size 0.0762 0.0762)
			(layers "B.Cu" "B.Mask" "B.Paste")
			(net "GND")
			(options
				(clearance outline)
				(anchor circle)
			)
			(primitives
				(gr_poly
					(pts
						(arc
							(start 0.1524 0.127)
							(mid 0.137521 0.162921)
							(end 0.1016 0.1778)
						)
						(arc
							(start -0.1016 0.1778)
							(mid -0.137521 0.162921)
							(end -0.1524 0.127)
						)
						(arc
							(start -0.1524 -0.127)
							(mid -0.137521 -0.162921)
							(end -0.1016 -0.1778)
						)
						(arc
							(start 0.1016 -0.1778)
							(mid 0.137521 -0.162921)
							(end 0.1524 -0.127)
						)
					)
					(width 0)
					(fill yes)
				)
			)
		)
	)
	(footprint ""
		(layer "B.Cu")
		(at 224.867724 -190.601092)
		(property "Reference" "R4141"
			(at 0 0 0)
			(layer "B.SilkS")
			(hide yes)
			(effects
				(font
					(size 1.27 1.27)
				)
				(justify mirror)
			)
		)
		(property "Value" "4K7R2F-GP"
			(at -0.064008 -3.993896 0)
			(unlocked yes)
			(layer "B.Fab")
			(hide yes)
			(effects
				(font
					(size 1.016 1.016)
					(thickness 0.1524)
				)
				(justify mirror)
			)
		)
		(property "Device Type" "R402H16"
			(at -0.064008 -5.517896 0)
			(unlocked yes)
			(layer "B.Fab")
			(hide yes)
			(effects
				(font
					(size 1.016 1.016)
					(thickness 0.1524)
				)
				(justify mirror)
			)
		)
		(duplicate_pad_numbers_are_jumpers no)
		(fp_line
			(start -0.508 -0.9398)
			(end 0.508 -0.9398)
			(stroke
				(width 0.1524)
				(type default)
			)
			(layer "B.SilkS")
		)
		(fp_line
			(start 0.508 -0.9398)
			(end 0.508 0.9398)
			(stroke
				(width 0.1524)
				(type default)
			)
			(layer "B.SilkS")
		)
		(fp_rect
			(start 0.508 0.9398)
			(end -0.508 -0.9398)
			(stroke
				(width 0)
				(type default)
			)
			(fill no)
			(layer "B.CrtYd")
		)
		(fp_rect
			(start 0.508 0.9398)
			(end -0.508 -0.9398)
			(stroke
				(width 0)
				(type default)
			)
			(fill no)
			(layer "B.Fab")
		)
		(pad "1" smd custom
			(at 0 -0.4445 180)
			(size 0.1397 0.1397)
			(layers "B.Cu" "B.Mask" "B.Paste")
			(net "SSD_PRSNT#8")
			(options
				(clearance outline)
				(anchor circle)
			)
			(primitives
				(gr_poly
					(pts
						(arc
							(start -0.1778 0.2794)
							(mid -0.249642 0.249642)
							(end -0.2794 0.1778)
						)
						(arc
							(start -0.2794 -0.1778)
							(mid -0.249642 -0.249642)
							(end -0.1778 -0.2794)
						)
						(arc
							(start 0.1778 -0.2794)
							(mid 0.249642 -0.249642)
							(end 0.2794 -0.1778)
						)
						(arc
							(start 0.2794 0.1778)
							(mid 0.249642 0.249642)
							(end 0.1778 0.2794)
						)
					)
					(width 0)
					(fill yes)
				)
			)
		)
		(pad "2" smd custom
			(at 0 0.4445 180)
			(size 0.1397 0.1397)
			(layers "B.Cu" "B.Mask" "B.Paste")
			(net "P3V3_STBY")
			(options
				(clearance outline)
				(anchor circle)
			)
			(primitives
				(gr_poly
					(pts
						(arc
							(start -0.1778 0.2794)
							(mid -0.249642 0.249642)
							(end -0.2794 0.1778)
						)
						(arc
							(start -0.2794 -0.1778)
							(mid -0.249642 -0.249642)
							(end -0.1778 -0.2794)
						)
						(arc
							(start 0.1778 -0.2794)
							(mid 0.249642 -0.249642)
							(end 0.2794 -0.1778)
						)
						(arc
							(start 0.2794 0.1778)
							(mid 0.249642 0.249642)
							(end 0.1778 0.2794)
						)
					)
					(width 0)
					(fill yes)
				)
			)
		)
	)
)
